# BASEBOARD_FAB2 (Tioga Pass) — schematic netlist excerpt (pin names and nets, part order shuffled) for the footprints in the layout excerpt that follows; sources: Cadence DE-HDL packaged netlist, KiCad conversion of Wiwynn_Tioga_Pass_MB.brd

C7G18  CAP  0.22UF 16V 10% X7R  pkg 0402  page 105 : A = P3E_CPU0_PE2_SS_TXN<9> ; B = P3E_CPU0_PE2_SS_C_TXN<9>
C7F4  CAP  0.1UF 25V 10% X7R  pkg 0603LF  page 231 : A = VR_PVPP_ABC_PHASE ; B = VR_PVPP_ABC_BOOT_R
R8C24  RES  0.0 5% CHIP  pkg 0402  page 118 : A = FM_GBE_LOM_DISABLE_N ; B = FM_1GB_LOM_DISABLE_N

(kicad_pcb
	(version 20260206)
	(generator "pcbnew")
	(generator_version "10.0")
	(general
		(thickness 1.6)
		(legacy_teardrops no)
	)
	(paper "A4")
	(title_block
		(title "Wiwynn_Tioga_Pass_MB.brd")
		(comment 1 "Tioga Pass / footprints 532-534 of 4770")
	)
	(layers
		(0 "F.Cu" signal "TOP")
		(4 "In1.Cu" signal "L2GND")
		(6 "In2.Cu" signal "L3")
		(8 "In3.Cu" signal "L4GND")
		(10 "In4.Cu" signal "L5")
		(12 "In5.Cu" signal "L6GND")
		(14 "In6.Cu" signal "L7VCC")
		(16 "In7.Cu" signal "L8VCC")
		(18 "In8.Cu" signal "L9GND")
		(20 "In9.Cu" signal "L10")
		(22 "In10.Cu" signal "L11GND")
		(24 "In11.Cu" signal "L12")
		(26 "In12.Cu" signal "L13GND")
		(2 "B.Cu" signal "BOTTOM")
		(9 "F.Adhes" user "F.Adhesive")
		(11 "B.Adhes" user "B.Adhesive")
		(13 "F.Paste" user "Package Geometry/Pastemask Top")
		(15 "B.Paste" user "Package Geometry/Pastemask Bottom")
		(5 "F.SilkS" user "Ref Des/Silkscreen Top")
		(7 "B.SilkS" user "Ref Des/Silkscreen Bottom")
		(1 "F.Mask" user "Board Geometry/Soldermask Top")
		(3 "B.Mask" user "Board Geometry/Soldermask Bottom")
		(17 "Dwgs.User" user "User.Drawings")
		(19 "Cmts.User" user "User.Comments")
		(21 "Eco1.User" user "User.Eco1")
		(23 "Eco2.User" user "User.Eco2")
		(25 "Edge.Cuts" user "Board Geometry/Outline")
		(27 "Margin" user)
		(31 "F.CrtYd" user "Package Geometry/Place Bound Top")
		(29 "B.CrtYd" user "Package Geometry/Place Bound Bottom")
		(35 "F.Fab" user "Ref Des/Assembly Top")
		(33 "B.Fab" user "Ref Des/Assembly Bottom")
	)
	(footprint ""
		(layer "F.Cu")
		(at 338.235036 -25.265126 90)
		(property "Reference" "C7F4"
			(at 0 0 90)
			(layer "F.SilkS")
			(hide yes)
			(effects
				(font
					(size 1.27 1.27)
				)
			)
		)
		(property "Value" ""
			(at 0 0 90)
			(layer "F.Fab")
			(effects
				(font
					(size 1.27 1.27)
				)
			)
		)
		(duplicate_pad_numbers_are_jumpers no)
		(fp_rect
			(start 0.4953 1.6002)
			(end -0.4953 -0.2032)
			(stroke
				(width 0)
				(type default)
			)
			(fill no)
			(layer "F.CrtYd")
		)
		(fp_line
			(start 0.4953 -0.2032)
			(end 0.4953 1.6002)
			(stroke
				(width 0.1)
				(type default)
			)
			(layer "F.Fab")
		)
		(fp_line
			(start -0.4953 -0.2032)
			(end 0.4953 -0.2032)
			(stroke
				(width 0.1)
				(type default)
			)
			(layer "F.Fab")
		)
		(fp_line
			(start 0.4953 1.6002)
			(end -0.4953 1.6002)
			(stroke
				(width 0.1)
				(type default)
			)
			(layer "F.Fab")
		)
		(fp_line
			(start -0.4953 1.6002)
			(end -0.4953 -0.2032)
			(stroke
				(width 0.1)
				(type default)
			)
			(layer "F.Fab")
		)
		(pad "1" smd rect
			(at 0 0 90)
			(size 0.762 0.889)
			(layers "F.Cu" "F.Mask" "F.Paste")
			(net "VR_PVPP_ABC_PHASE")
		)
		(pad "2" smd rect
			(at 0 1.397 90)
			(size 0.762 0.889)
			(layers "F.Cu" "F.Mask" "F.Paste")
			(net "VR_PVPP_ABC_BOOT_R")
		)
		(zone
			(layer "F.Cu")
			(hatch none 0.5)
			(connect_pads
				(clearance 0)
			)
			(min_thickness 0.25)
			(keepout
				(tracks not_allowed)
				(vias allowed)
				(pads allowed)
				(copperpour not_allowed)
				(footprints allowed)
			)
			(placement
				(enabled no)
				(sheetname "")
			)
			(fill
				(thermal_gap 0.5)
				(thermal_bridge_width 0.5)
				(island_removal_mode 0)
			)
			(polygon
				(pts
					(xy 339.187536 -25.646126) (xy 338.679536 -25.646126) (xy 338.679536 -24.884126) (xy 339.187536 -24.884126)
				)
			)
		)
	)
	(footprint ""
		(layer "F.Cu")
		(at 377.567444 -10.916158)
		(property "Reference" "C7G18"
			(at 0 0 0)
			(layer "F.SilkS")
			(hide yes)
			(effects
				(font
					(size 1.27 1.27)
				)
			)
		)
		(property "Value" ""
			(at 0 0 0)
			(layer "F.Fab")
			(effects
				(font
					(size 1.27 1.27)
				)
			)
		)
		(duplicate_pad_numbers_are_jumpers no)
		(fp_rect
			(start -0.3048 0.9906)
			(end 0.3048 -0.1016)
			(stroke
				(width 0)
				(type default)
			)
			(fill no)
			(layer "F.CrtYd")
		)
		(fp_line
			(start -0.3048 -0.1016)
			(end -0.3048 0.9906)
			(stroke
				(width 0.1)
				(type default)
			)
			(layer "F.Fab")
		)
		(fp_line
			(start -0.3048 0.9906)
			(end 0.3048 0.9906)
			(stroke
				(width 0.1)
				(type default)
			)
			(layer "F.Fab")
		)
		(fp_line
			(start 0.3048 -0.1016)
			(end -0.3048 -0.1016)
			(stroke
				(width 0.1)
				(type default)
			)
			(layer "F.Fab")
		)
		(fp_line
			(start 0.3048 0.9906)
			(end 0.3048 -0.1016)
			(stroke
				(width 0.1)
				(type default)
			)
			(layer "F.Fab")
		)
		(pad "1" smd rect
			(at 0 0)
			(size 0.508 0.508)
			(layers "F.Cu" "F.Mask" "F.Paste")
			(net "P3E_CPU0_PE2_SS_TXN<9>")
		)
		(pad "2" smd rect
			(at 0 0.889)
			(size 0.508 0.508)
			(layers "F.Cu" "F.Mask" "F.Paste")
			(net "P3E_CPU0_PE2_SS_C_TXN<9>")
		)
		(zone
			(layer "F.Cu")
			(hatch none 0.5)
			(connect_pads
				(clearance 0)
			)
			(min_thickness 0.25)
			(keepout
				(tracks allowed)
				(vias not_allowed)
				(pads allowed)
				(copperpour not_allowed)
				(footprints allowed)
			)
			(placement
				(enabled no)
				(sheetname "")
			)
			(fill
				(thermal_gap 0.5)
				(thermal_bridge_width 0.5)
				(island_removal_mode 0)
			)
			(polygon
				(pts
					(xy 377.313444 -10.281158) (xy 377.821444 -10.281158) (xy 377.821444 -10.662158) (xy 377.313444 -10.662158)
				)
			)
		)
	)
	(footprint ""
		(layer "F.Cu")
		(at 408.813 -102.9335 180)
		(property "Reference" "R8C24"
			(at 0 0 180)
			(layer "F.SilkS")
			(hide yes)
			(effects
				(font
					(size 1.27 1.27)
				)
			)
		)
		(property "Value" ""
			(at 0 0 180)
			(layer "F.Fab")
			(effects
				(font
					(size 1.27 1.27)
				)
			)
		)
		(duplicate_pad_numbers_are_jumpers no)
		(fp_poly
			(pts
				(xy -0.2794 -0.1016) (xy 0.2794 -0.1016) (xy 0.2794 0.9906) (xy -0.2794 0.9906)
			)
			(stroke
				(width 0)
				(type default)
			)
			(fill no)
			(layer "F.CrtYd")
		)
		(fp_line
			(start 0.2794 0.9906)
			(end 0.2794 -0.1016)
			(stroke
				(width 0.1)
				(type default)
			)
			(layer "F.Fab")
		)
		(fp_line
			(start 0.2794 -0.1016)
			(end -0.2794 -0.1016)
			(stroke
				(width 0.1)
				(type default)
			)
			(layer "F.Fab")
		)
		(fp_line
			(start -0.2794 0.9906)
			(end 0.2794 0.9906)
			(stroke
				(width 0.1)
				(type default)
			)
			(layer "F.Fab")
		)
		(fp_line
			(start -0.2794 -0.1016)
			(end -0.2794 0.9906)
			(stroke
				(width 0.1)
				(type default)
			)
			(layer "F.Fab")
		)
		(pad "1" smd rect
			(at 0 0 180)
			(size 0.508 0.508)
			(layers "F.Cu" "F.Mask" "F.Paste")
			(net "FM_GBE_LOM_DISABLE_N")
		)
		(pad "2" smd rect
			(at 0 0.889 180)
			(size 0.508 0.508)
			(layers "F.Cu" "F.Mask" "F.Paste")
			(net "FM_1GB_LOM_DISABLE_N")
		)
		(zone
			(layer "F.Cu")
			(hatch none 0.5)
			(connect_pads
				(clearance 0)
			)
			(min_thickness 0.25)
			(keepout
				(tracks not_allowed)
				(vias allowed)
				(pads allowed)
				(copperpour not_allowed)
				(footprints allowed)
			)
			(placement
				(enabled no)
				(sheetname "")
			)
			(fill
				(thermal_gap 0.5)
				(thermal_bridge_width 0.5)
				(island_removal_mode 0)
			)
			(polygon
				(pts
					(xy 409.067 -103.5685) (xy 408.559 -103.5685) (xy 408.559 -103.1875) (xy 409.067 -103.1875)
				)
			)
		)
		(zone
			(layer "F.Cu")
			(hatch none 0.5)
			(connect_pads
				(clearance 0)
			)
			(min_thickness 0.25)
			(keepout
				(tracks allowed)
				(vias not_allowed)
				(pads allowed)
				(copperpour not_allowed)
				(footprints allowed)
			)
			(placement
				(enabled no)
				(sheetname "")
			)
			(fill
				(thermal_gap 0.5)
				(thermal_bridge_width 0.5)
				(island_removal_mode 0)
			)
			(polygon
				(pts
					(xy 409.067 -103.1875) (xy 408.559 -103.1875) (xy 408.559 -103.5685) (xy 409.067 -103.5685)
				)
			)
		)
	)
)
